# TIMECARD (Time Appliance Project (Time Card)) — schematic netlist excerpt (pin names and nets, part order shuffled) for the footprints in the layout excerpt that follows; sources: Cadence DE-HDL packaged netlist, KiCad conversion of R4006-B0001-02_R01.brd

R491  RESISTOR  3.24KOHM 1%  pkg SMC_0402R_H014  page 33 : \1\ = UNNAMED_525_ISL80101IRAJZDFN10_ ; \2\ = SG
R259  RESISTOR  330OHM 1%  pkg SMC_0402R_H016  page 26 : \1\ = UNNAMED_14_OPTICAL_I136_A ; \2\ = XP3R3V_FPGA

(kicad_pcb
	(version 20260206)
	(generator "pcbnew")
	(generator_version "10.0")
	(general
		(thickness 1.6)
		(legacy_teardrops no)
	)
	(paper "A4")
	(title_block
		(title "timecard-production-celestica-r4006 — R4006-B0001-02_R01.brd")
		(comment 1 "Time Appliance Project (Time Card) / footprints 913-914 of 1113")
	)
	(layers
		(0 "F.Cu" signal "TOP")
		(4 "In1.Cu" signal "L02_GND1")
		(6 "In2.Cu" signal "L03_SIG1")
		(8 "In3.Cu" signal "L04_GND2")
		(10 "In4.Cu" signal "L05_VCC1")
		(12 "In5.Cu" signal "L06_VCC2")
		(14 "In6.Cu" signal "L07_GND3")
		(16 "In7.Cu" signal "L08_SIG2")
		(18 "In8.Cu" signal "L09_GND4")
		(2 "B.Cu" signal "BOTTOM")
		(9 "F.Adhes" user "F.Adhesive")
		(11 "B.Adhes" user "B.Adhesive")
		(13 "F.Paste" user "Package Geometry/Pastemask Top")
		(15 "B.Paste" user "Package Geometry/Pastemask Bottom")
		(5 "F.SilkS" user "Ref Des/Silkscreen Top")
		(7 "B.SilkS" user "Ref Des/Silkscreen Bottom")
		(1 "F.Mask" user "Board Geometry/Soldermask Top")
		(3 "B.Mask" user "Board Geometry/Soldermask Bottom")
		(17 "Dwgs.User" user "User.Drawings")
		(19 "Cmts.User" user "User.Comments")
		(21 "Eco1.User" user "User.Eco1")
		(23 "Eco2.User" user "User.Eco2")
		(25 "Edge.Cuts" user "Board Geometry/Outline")
		(27 "Margin" user)
		(31 "F.CrtYd" user "Package Geometry/Place Bound Top")
		(29 "B.CrtYd" user "Package Geometry/Place Bound Bottom")
		(35 "F.Fab" user "Ref Des/Assembly Top")
		(33 "B.Fab" user "Ref Des/Assembly Bottom")
	)
	(footprint ""
		(layer "B.Cu")
		(at 144.018 -107.696 90)
		(property "Reference" "R259"
			(at -0.762 1.16205 270)
			(unlocked yes)
			(layer "B.SilkS")
			(effects
				(font
					(size 0.635 0.4064)
					(thickness 0.1524)
				)
				(justify mirror)
			)
		)
		(property "Value" "VAL*"
			(at -0.02032 2.13233 90)
			(unlocked yes)
			(layer "B.Fab")
			(hide yes)
			(effects
				(font
					(size 0.7874 0.5842)
					(thickness 0.1524)
				)
				(justify mirror)
			)
		)
		(property "Device Type" "RESISTOR-G155-13300-01,330OHM,A"
			(at -0.008382 1.210564 90)
			(unlocked yes)
			(layer "B.Fab")
			(hide yes)
			(effects
				(font
					(size 0.7874 0.5842)
					(thickness 0.1524)
				)
				(justify mirror)
			)
		)
		(property "User Part Number" "PARTNUM*"
			(at -0.02032 4.024884 90)
			(unlocked yes)
			(layer "Cmts.User")
			(hide yes)
			(effects
				(font
					(size 0.7874 0.5842)
					(thickness 0.1524)
				)
				(justify mirror)
			)
		)
		(property "Tolerance" "TOL*"
			(at -0.044704 3.05435 90)
			(unlocked yes)
			(layer "Cmts.User")
			(hide yes)
			(effects
				(font
					(size 0.7874 0.5842)
					(thickness 0.1524)
				)
				(justify mirror)
			)
		)
		(duplicate_pad_numbers_are_jumpers no)
		(fp_line
			(start 1.143 -0.5588)
			(end 1.143 0.5588)
			(stroke
				(width 0.1)
				(type default)
			)
			(layer "B.SilkS")
		)
		(fp_line
			(start -1.143 -0.5588)
			(end 1.143 -0.5588)
			(stroke
				(width 0.1)
				(type default)
			)
			(layer "B.SilkS")
		)
		(fp_line
			(start 1.143 0.5588)
			(end -1.143 0.5588)
			(stroke
				(width 0.1)
				(type default)
			)
			(layer "B.SilkS")
		)
		(fp_line
			(start -1.143 0.5588)
			(end -1.143 -0.5588)
			(stroke
				(width 0.1)
				(type default)
			)
			(layer "B.SilkS")
		)
		(fp_rect
			(start -1.143 -0.5588)
			(end 1.143 0.5588)
			(stroke
				(width 0)
				(type default)
			)
			(fill no)
			(layer "B.CrtYd")
		)
		(fp_line
			(start 0.508 -0.3048)
			(end 0.508 0.3048)
			(stroke
				(width 0.1)
				(type default)
			)
			(layer "B.Fab")
		)
		(fp_line
			(start -0.508 -0.3048)
			(end 0.508 -0.3048)
			(stroke
				(width 0.1)
				(type default)
			)
			(layer "B.Fab")
		)
		(fp_line
			(start 0.508 0.3048)
			(end -0.508 0.3048)
			(stroke
				(width 0.1)
				(type default)
			)
			(layer "B.Fab")
		)
		(fp_line
			(start -0.508 0.3048)
			(end -0.508 -0.3048)
			(stroke
				(width 0.1)
				(type default)
			)
			(layer "B.Fab")
		)
		(pad "1" smd rect
			(at 0.5334 0 270)
			(size 0.7112 0.6096)
			(layers "B.Cu" "B.Mask" "B.Paste")
			(net "UNNAMED_14_OPTICAL_I136_A")
		)
		(pad "2" smd rect
			(at -0.5334 0 270)
			(size 0.7112 0.6096)
			(layers "B.Cu" "B.Mask" "B.Paste")
			(net "XP3R3V_FPGA")
		)
		(zone
			(layer "B.Cu")
			(hatch none 0.5)
			(connect_pads
				(clearance 0)
			)
			(min_thickness 0.25)
			(keepout
				(tracks allowed)
				(vias not_allowed)
				(pads allowed)
				(copperpour not_allowed)
				(footprints allowed)
			)
			(placement
				(enabled no)
				(sheetname "")
			)
			(fill
				(thermal_gap 0.5)
				(thermal_bridge_width 0.5)
				(island_removal_mode 0)
			)
			(polygon
				(pts
					(xy 143.7132 -107.6198) (xy 144.3228 -107.6198) (xy 144.3228 -107.7722) (xy 143.7132 -107.7722)
				)
			)
		)
	)
	(footprint ""
		(layer "B.Cu")
		(at 38.1 -76.2)
		(property "Reference" "R491"
			(at -0.508 -1.10363 0)
			(unlocked yes)
			(layer "B.SilkS")
			(effects
				(font
					(size 0.7874 0.5842)
					(thickness 0.1524)
				)
				(justify mirror)
			)
		)
		(property "Value" "VAL*"
			(at -0.02032 2.13233 0)
			(unlocked yes)
			(layer "B.Fab")
			(hide yes)
			(effects
				(font
					(size 0.7874 0.5842)
					(thickness 0.1524)
				)
				(justify mirror)
			)
		)
		(property "Tolerance" "TOL*"
			(at -0.044704 3.05435 0)
			(unlocked yes)
			(layer "Cmts.User")
			(hide yes)
			(effects
				(font
					(size 0.7874 0.5842)
					(thickness 0.1524)
				)
				(justify mirror)
			)
		)
		(property "User Part Number" "PARTNUM*"
			(at -0.02032 4.024884 0)
			(unlocked yes)
			(layer "Cmts.User")
			(hide yes)
			(effects
				(font
					(size 0.7874 0.5842)
					(thickness 0.1524)
				)
				(justify mirror)
			)
		)
		(property "Device Type" "RESISTOR-G155-03241-01,3.24KOHA"
			(at -0.008382 1.210564 0)
			(unlocked yes)
			(layer "B.Fab")
			(hide yes)
			(effects
				(font
					(size 0.7874 0.5842)
					(thickness 0.1524)
				)
				(justify mirror)
			)
		)
		(duplicate_pad_numbers_are_jumpers no)
		(fp_line
			(start -1.143 -0.5588)
			(end 1.143 -0.5588)
			(stroke
				(width 0.1)
				(type default)
			)
			(layer "B.SilkS")
		)
		(fp_line
			(start -1.143 0.5588)
			(end -1.143 -0.5588)
			(stroke
				(width 0.1)
				(type default)
			)
			(layer "B.SilkS")
		)
		(fp_line
			(start 1.143 -0.5588)
			(end 1.143 0.5588)
			(stroke
				(width 0.1)
				(type default)
			)
			(layer "B.SilkS")
		)
		(fp_line
			(start 1.143 0.5588)
			(end -1.143 0.5588)
			(stroke
				(width 0.1)
				(type default)
			)
			(layer "B.SilkS")
		)
		(fp_poly
			(pts
				(xy 1.143 0.5588) (xy -1.143 0.5588) (xy -1.143 -0.5588) (xy 1.143 -0.5588)
			)
			(stroke
				(width 0)
				(type default)
			)
			(fill no)
			(layer "B.CrtYd")
		)
		(fp_line
			(start -0.508 -0.3048)
			(end 0.508 -0.3048)
			(stroke
				(width 0.1)
				(type default)
			)
			(layer "B.Fab")
		)
		(fp_line
			(start -0.508 0.3048)
			(end -0.508 -0.3048)
			(stroke
				(width 0.1)
				(type default)
			)
			(layer "B.Fab")
		)
		(fp_line
			(start 0.508 -0.3048)
			(end 0.508 0.3048)
			(stroke
				(width 0.1)
				(type default)
			)
			(layer "B.Fab")
		)
		(fp_line
			(start 0.508 0.3048)
			(end -0.508 0.3048)
			(stroke
				(width 0.1)
				(type default)
			)
			(layer "B.Fab")
		)
		(pad "1" smd rect
			(at 0.5334 0 180)
			(size 0.7112 0.6096)
			(layers "B.Cu" "B.Mask" "B.Paste")
			(net "UNNAMED_525_ISL80101IRAJZDFN10_")
		)
		(pad "2" smd rect
			(at -0.5334 0 180)
			(size 0.7112 0.6096)
			(layers "B.Cu" "B.Mask" "B.Paste")
			(net "SG")
		)
		(zone
			(layer "B.Cu")
			(hatch none 0.5)
			(connect_pads
				(clearance 0)
			)
			(min_thickness 0.25)
			(keepout
				(tracks allowed)
				(vias not_allowed)
				(pads allowed)
				(copperpour not_allowed)
				(footprints allowed)
			)
			(placement
				(enabled no)
				(sheetname "")
			)
			(fill
				(thermal_gap 0.5)
				(thermal_bridge_width 0.5)
				(island_removal_mode 0)
			)
			(polygon
				(pts
					(xy 38.1762 -75.8952) (xy 38.1762 -76.5048) (xy 38.0238 -76.5048) (xy 38.0238 -75.8952)
				)
			)
		)
		(zone
			(layer "B.Cu")
			(hatch none 0.5)
			(connect_pads
				(clearance 0)
			)
			(min_thickness 0.25)
			(keepout
				(tracks not_allowed)
				(vias allowed)
				(pads allowed)
				(copperpour not_allowed)
				(footprints allowed)
			)
			(placement
				(enabled no)
				(sheetname "")
			)
			(fill
				(thermal_gap 0.5)
				(thermal_bridge_width 0.5)
				(island_removal_mode 0)
			)
			(polygon
				(pts
					(xy 38.1762 -75.8952) (xy 38.1762 -76.5048) (xy 38.0238 -76.5048) (xy 38.0238 -75.8952)
				)
			)
		)
	)
)
